# T6G (Grand Teton) — schematic netlist excerpt (pin names and nets, part order shuffled) for the footprints in the layout excerpt that follows; sources: Cadence DE-HDL packaged netlist, KiCad conversion of 04192023_DAF0TMB3IC0_F0TG_MB_C_brd_V02_OCP.brd

C2277  Q_CAP  22UF 4V 20% X6S  pkg C0402  page 72 : A = PVDDCR_SOC_P1 ; B = GND
C516  Q_CAP  0.1UF 10V 10% X7S  pkg C0201  page 279 : A = P1V8_CPU0_RT0_1A_1D ; B = GND
C127  Q_CAP  10UF 6.3V 20% X6S  pkg C0402  page 334 : A = P1V8_CPU1_RT_1D ; B = GND

(kicad_pcb
	(version 20260206)
	(generator "pcbnew")
	(generator_version "10.0")
	(general
		(thickness 1.6)
		(legacy_teardrops no)
	)
	(paper "A4")
	(title_block
		(title "04192023_DAF0TMB3IC0_F0TG_MB_C_brd_V02_OCP.brd")
		(comment 1 "Grand Teton / footprints 7576-7578 of 8354")
	)
	(layers
		(0 "F.Cu" signal "TOP")
		(4 "In1.Cu" signal "GND")
		(6 "In2.Cu" signal "IN1")
		(8 "In3.Cu" signal "GND1")
		(10 "In4.Cu" signal "IN2")
		(12 "In5.Cu" signal "GND2")
		(14 "In6.Cu" signal "IN3")
		(16 "In7.Cu" signal "GND3")
		(18 "In8.Cu" signal "VCC")
		(20 "In9.Cu" signal "VCC1")
		(22 "In10.Cu" signal "GND4")
		(24 "In11.Cu" signal "IN4")
		(26 "In12.Cu" signal "GND5")
		(28 "In13.Cu" signal "IN5")
		(30 "In14.Cu" signal "GND6")
		(32 "In15.Cu" signal "IN6")
		(34 "In16.Cu" signal "GND7")
		(2 "B.Cu" signal "BOTTOM")
		(9 "F.Adhes" user "F.Adhesive")
		(11 "B.Adhes" user "B.Adhesive")
		(13 "F.Paste" user "Package Geometry/Pastemask Top")
		(15 "B.Paste" user "Package Geometry/Pastemask Bottom")
		(5 "F.SilkS" user "Ref Des/Silkscreen Top")
		(7 "B.SilkS" user "Ref Des/Silkscreen Bottom")
		(1 "F.Mask" user "Board Geometry/Soldermask Top")
		(3 "B.Mask" user "Board Geometry/Soldermask Bottom")
		(17 "Dwgs.User" user "User.Drawings")
		(19 "Cmts.User" user "User.Comments")
		(21 "Eco1.User" user "User.Eco1")
		(23 "Eco2.User" user "User.Eco2")
		(25 "Edge.Cuts" user "Board Geometry/Outline")
		(27 "Margin" user)
		(31 "F.CrtYd" user "Package Geometry/Place Bound Top")
		(29 "B.CrtYd" user "Package Geometry/Place Bound Bottom")
		(35 "F.Fab" user "Ref Des/Assembly Top")
		(33 "B.Fab" user "Ref Des/Assembly Bottom")
	)
	(footprint ""
		(layer "B.Cu")
		(at 314.318142 -396.393162 -90)
		(property "Reference" "C516"
			(at 0 0 90)
			(layer "B.SilkS")
			(hide yes)
			(effects
				(font
					(size 1.27 1.27)
				)
				(justify mirror)
			)
		)
		(property "Value" ""
			(at 0 0 90)
			(layer "B.Fab")
			(effects
				(font
					(size 1.27 1.27)
				)
				(justify mirror)
			)
		)
		(duplicate_pad_numbers_are_jumpers no)
		(fp_line
			(start -0.299974 0.150114)
			(end 0.299974 0.150114)
			(stroke
				(width 0.1)
				(type default)
			)
			(layer "B.Fab")
		)
		(fp_line
			(start 0.299974 0.150114)
			(end 0.299974 -0.150114)
			(stroke
				(width 0.1)
				(type default)
			)
			(layer "B.Fab")
		)
		(fp_line
			(start -0.299974 -0.150114)
			(end -0.299974 0.150114)
			(stroke
				(width 0.1)
				(type default)
			)
			(layer "B.Fab")
		)
		(fp_line
			(start 0.299974 -0.150114)
			(end -0.299974 -0.150114)
			(stroke
				(width 0.1)
				(type default)
			)
			(layer "B.Fab")
		)
		(pad "1" smd rect
			(at 0.2667 0 90)
			(size 0.3048 0.381)
			(layers "B.Cu" "B.Mask" "B.Paste")
			(net "P1V8_CPU0_RT0_1A_1D")
		)
		(pad "2" smd rect
			(at -0.2667 0 90)
			(size 0.3048 0.381)
			(layers "B.Cu" "B.Mask" "B.Paste")
			(net "GND")
		)
	)
	(footprint ""
		(layer "B.Cu")
		(at 111.800386 -251.400564 180)
		(property "Reference" "C2277"
			(at 0 0 0)
			(layer "B.SilkS")
			(hide yes)
			(effects
				(font
					(size 1.27 1.27)
				)
				(justify mirror)
			)
		)
		(property "Value" ""
			(at 0 0 0)
			(layer "B.Fab")
			(effects
				(font
					(size 1.27 1.27)
				)
				(justify mirror)
			)
		)
		(duplicate_pad_numbers_are_jumpers no)
		(fp_line
			(start 0.7874 0.4064)
			(end 0.7874 -0.4064)
			(stroke
				(width 0.1524)
				(type default)
			)
			(layer "B.SilkS")
		)
		(fp_line
			(start 0.7874 -0.4064)
			(end -0.7874 -0.4064)
			(stroke
				(width 0.1524)
				(type default)
			)
			(layer "B.SilkS")
		)
		(fp_line
			(start -0.7874 0.4064)
			(end 0.7874 0.4064)
			(stroke
				(width 0.1524)
				(type default)
			)
			(layer "B.SilkS")
		)
		(fp_line
			(start -0.7874 -0.4064)
			(end -0.7874 0.4064)
			(stroke
				(width 0.1524)
				(type default)
			)
			(layer "B.SilkS")
		)
		(fp_line
			(start 0.67945 0.3048)
			(end 0.67945 -0.305054)
			(stroke
				(width 0.1)
				(type default)
			)
			(layer "B.Fab")
		)
		(fp_line
			(start 0.67945 -0.305054)
			(end 0.12065 -0.305054)
			(stroke
				(width 0.1)
				(type default)
			)
			(layer "B.Fab")
		)
		(fp_line
			(start 0.12065 0.3048)
			(end 0.67945 0.3048)
			(stroke
				(width 0.1)
				(type default)
			)
			(layer "B.Fab")
		)
		(fp_line
			(start 0.12065 0.2794)
			(end 0.12065 0.3048)
			(stroke
				(width 0.1)
				(type default)
			)
			(layer "B.Fab")
		)
		(fp_line
			(start 0.12065 -0.2794)
			(end -0.12065 -0.2794)
			(stroke
				(width 0.1)
				(type default)
			)
			(layer "B.Fab")
		)
		(fp_line
			(start 0.12065 -0.305054)
			(end 0.12065 -0.2794)
			(stroke
				(width 0.1)
				(type default)
			)
			(layer "B.Fab")
		)
		(fp_line
			(start -0.120396 0.3048)
			(end -0.120396 0.2794)
			(stroke
				(width 0.1)
				(type default)
			)
			(layer "B.Fab")
		)
		(fp_line
			(start -0.120396 0.2794)
			(end 0.12065 0.2794)
			(stroke
				(width 0.1)
				(type default)
			)
			(layer "B.Fab")
		)
		(fp_line
			(start -0.12065 -0.2794)
			(end -0.12065 -0.3048)
			(stroke
				(width 0.1)
				(type default)
			)
			(layer "B.Fab")
		)
		(fp_line
			(start -0.12065 -0.3048)
			(end -0.67945 -0.3048)
			(stroke
				(width 0.1)
				(type default)
			)
			(layer "B.Fab")
		)
		(fp_line
			(start -0.67945 0.3048)
			(end -0.120396 0.3048)
			(stroke
				(width 0.1)
				(type default)
			)
			(layer "B.Fab")
		)
		(fp_line
			(start -0.67945 -0.3048)
			(end -0.67945 0.3048)
			(stroke
				(width 0.1)
				(type default)
			)
			(layer "B.Fab")
		)
		(pad "1" smd circle
			(at 0.40005 0)
			(size 0 0)
			(layers "B.Cu" "B.Mask" "B.Paste")
			(net "PVDDCR_SOC_P1")
		)
		(pad "2" smd circle
			(at -0.40005 0)
			(size 0 0)
			(layers "B.Cu" "B.Mask" "B.Paste")
			(net "GND")
		)
	)
	(footprint ""
		(layer "B.Cu")
		(at 104.580182 -386.745988 -90)
		(property "Reference" "C127"
			(at 0 0 90)
			(layer "B.SilkS")
			(hide yes)
			(effects
				(font
					(size 1.27 1.27)
				)
				(justify mirror)
			)
		)
		(property "Value" ""
			(at 0 0 90)
			(layer "B.Fab")
			(effects
				(font
					(size 1.27 1.27)
				)
				(justify mirror)
			)
		)
		(duplicate_pad_numbers_are_jumpers no)
		(fp_line
			(start -0.7874 0.4064)
			(end 0.7874 0.4064)
			(stroke
				(width 0.1524)
				(type default)
			)
			(layer "B.SilkS")
		)
		(fp_line
			(start 0.7874 0.4064)
			(end 0.7874 -0.4064)
			(stroke
				(width 0.1524)
				(type default)
			)
			(layer "B.SilkS")
		)
		(fp_line
			(start -0.7874 -0.4064)
			(end -0.7874 0.4064)
			(stroke
				(width 0.1524)
				(type default)
			)
			(layer "B.SilkS")
		)
		(fp_line
			(start 0.7874 -0.4064)
			(end -0.7874 -0.4064)
			(stroke
				(width 0.1524)
				(type default)
			)
			(layer "B.SilkS")
		)
		(fp_line
			(start -0.67945 0.3048)
			(end -0.120396 0.3048)
			(stroke
				(width 0.1)
				(type default)
			)
			(layer "B.Fab")
		)
		(fp_line
			(start -0.120396 0.3048)
			(end -0.120396 0.2794)
			(stroke
				(width 0.1)
				(type default)
			)
			(layer "B.Fab")
		)
		(fp_line
			(start 0.12065 0.3048)
			(end 0.67945 0.3048)
			(stroke
				(width 0.1)
				(type default)
			)
			(layer "B.Fab")
		)
		(fp_line
			(start 0.67945 0.3048)
			(end 0.67945 -0.305054)
			(stroke
				(width 0.1)
				(type default)
			)
			(layer "B.Fab")
		)
		(fp_line
			(start -0.120396 0.2794)
			(end 0.12065 0.2794)
			(stroke
				(width 0.1)
				(type default)
			)
			(layer "B.Fab")
		)
		(fp_line
			(start 0.12065 0.2794)
			(end 0.12065 0.3048)
			(stroke
				(width 0.1)
				(type default)
			)
			(layer "B.Fab")
		)
		(fp_line
			(start -0.12065 -0.2794)
			(end -0.12065 -0.3048)
			(stroke
				(width 0.1)
				(type default)
			)
			(layer "B.Fab")
		)
		(fp_line
			(start 0.12065 -0.2794)
			(end -0.12065 -0.2794)
			(stroke
				(width 0.1)
				(type default)
			)
			(layer "B.Fab")
		)
		(fp_line
			(start -0.67945 -0.3048)
			(end -0.67945 0.3048)
			(stroke
				(width 0.1)
				(type default)
			)
			(layer "B.Fab")
		)
		(fp_line
			(start -0.12065 -0.3048)
			(end -0.67945 -0.3048)
			(stroke
				(width 0.1)
				(type default)
			)
			(layer "B.Fab")
		)
		(fp_line
			(start 0.12065 -0.305054)
			(end 0.12065 -0.2794)
			(stroke
				(width 0.1)
				(type default)
			)
			(layer "B.Fab")
		)
		(fp_line
			(start 0.67945 -0.305054)
			(end 0.12065 -0.305054)
			(stroke
				(width 0.1)
				(type default)
			)
			(layer "B.Fab")
		)
		(pad "1" smd circle
			(at 0.40005 0 90)
			(size 0 0)
			(layers "B.Cu" "B.Mask" "B.Paste")
			(net "P1V8_CPU1_RT_1D")
		)
		(pad "2" smd circle
			(at -0.40005 0 90)
			(size 0 0)
			(layers "B.Cu" "B.Mask" "B.Paste")
			(net "GND")
		)
	)
)
